# S9S_MB_2U (Grand Teton) — schematic netlist excerpt (pin names and nets, part order shuffled) for the footprints in the layout excerpt that follows; sources: Cadence DE-HDL packaged netlist, KiCad conversion of 03242023_DA0F0TMBIJ0_F0T_Motherboard_J_brd_V01_OCP.brd

PC304_P0_2  Q_CAP  22UF 16V 20% X6S  pkg C0805  page 267 : A = SW_P12V_PVCCIN_CPU0_FLT ; B = GND
C380  Q_CAP  47UF 4V 20% X6S  pkg C0805  page 76 : A = PVCCIN_CPU0 ; B = GND
C159  Q_CAP_DIFFBUS  DIFF BUS_0.22UF 6.3V 20% X6S  pkg C0201  page 178 : \1\ = DMI_CPU0_PCH_RX_C_DN<5> ; \2\ = DMI_CPU0_PCH_RX_DN<5>
PC1186_P0_4  Q_CAP  22UF 4V 20% X6S  pkg C0805  page 272 : A = PVCCFA_EHV_FIVRA_CPU0 ; B = GND

(kicad_pcb
	(version 20260206)
	(generator "pcbnew")
	(generator_version "10.0")
	(general
		(thickness 1.6)
		(legacy_teardrops no)
	)
	(paper "A4")
	(title_block
		(title "03242023_DA0F0TMBIJ0_F0T_Motherboard_J_brd_V01_OCP.brd")
		(comment 1 "Grand Teton / footprints 6014-6017 of 6105")
	)
	(layers
		(0 "F.Cu" signal "TOP")
		(4 "In1.Cu" signal "GND")
		(6 "In2.Cu" signal "IN1")
		(8 "In3.Cu" signal "GND1")
		(10 "In4.Cu" signal "IN2")
		(12 "In5.Cu" signal "GND2")
		(14 "In6.Cu" signal "IN3")
		(16 "In7.Cu" signal "GND3")
		(18 "In8.Cu" signal "VCC")
		(20 "In9.Cu" signal "VCC1")
		(22 "In10.Cu" signal "GND4")
		(24 "In11.Cu" signal "IN4")
		(26 "In12.Cu" signal "GND5")
		(28 "In13.Cu" signal "IN5")
		(30 "In14.Cu" signal "GND6")
		(32 "In15.Cu" signal "IN6")
		(34 "In16.Cu" signal "GND7")
		(2 "B.Cu" signal "BOTTOM")
		(9 "F.Adhes" user "F.Adhesive")
		(11 "B.Adhes" user "B.Adhesive")
		(13 "F.Paste" user "Package Geometry/Pastemask Top")
		(15 "B.Paste" user "Package Geometry/Pastemask Bottom")
		(5 "F.SilkS" user "Ref Des/Silkscreen Top")
		(7 "B.SilkS" user "Ref Des/Silkscreen Bottom")
		(1 "F.Mask" user "Board Geometry/Soldermask Top")
		(3 "B.Mask" user "Board Geometry/Soldermask Bottom")
		(17 "Dwgs.User" user "User.Drawings")
		(19 "Cmts.User" user "User.Comments")
		(21 "Eco1.User" user "User.Eco1")
		(23 "Eco2.User" user "User.Eco2")
		(25 "Edge.Cuts" user "Board Geometry/Outline")
		(27 "Margin" user)
		(31 "F.CrtYd" user "Package Geometry/Place Bound Top")
		(29 "B.CrtYd" user "Package Geometry/Place Bound Bottom")
		(35 "F.Fab" user "Ref Des/Assembly Top")
		(33 "B.Fab" user "Ref Des/Assembly Bottom")
	)
	(footprint ""
		(layer "B.Cu")
		(at 346.4687 -64.088264 90)
		(property "Reference" "C159"
			(at 0 0 90)
			(layer "B.SilkS")
			(hide yes)
			(effects
				(font
					(size 1.27 1.27)
				)
				(justify mirror)
			)
		)
		(property "Value" ""
			(at 0 0 90)
			(layer "B.Fab")
			(effects
				(font
					(size 1.27 1.27)
				)
				(justify mirror)
			)
		)
		(duplicate_pad_numbers_are_jumpers no)
		(fp_line
			(start 0.299974 -0.150114)
			(end -0.299974 -0.150114)
			(stroke
				(width 0.1)
				(type default)
			)
			(layer "B.Fab")
		)
		(fp_line
			(start -0.299974 -0.150114)
			(end -0.299974 0.150114)
			(stroke
				(width 0.1)
				(type default)
			)
			(layer "B.Fab")
		)
		(fp_line
			(start 0.299974 0.150114)
			(end 0.299974 -0.150114)
			(stroke
				(width 0.1)
				(type default)
			)
			(layer "B.Fab")
		)
		(fp_line
			(start -0.299974 0.150114)
			(end 0.299974 0.150114)
			(stroke
				(width 0.1)
				(type default)
			)
			(layer "B.Fab")
		)
		(pad "1" smd rect
			(at 0.2667 0 270)
			(size 0.3048 0.381)
			(layers "B.Cu" "B.Mask" "B.Paste")
			(net "DMI_CPU0_PCH_RX_C_DN<5>")
		)
		(pad "2" smd rect
			(at -0.2667 0 270)
			(size 0.3048 0.381)
			(layers "B.Cu" "B.Mask" "B.Paste")
			(net "DMI_CPU0_PCH_RX_DN<5>")
		)
	)
	(footprint ""
		(layer "B.Cu")
		(at 366.310418 -294.009826)
		(property "Reference" "C380"
			(at 0 0 0)
			(layer "B.SilkS")
			(hide yes)
			(effects
				(font
					(size 1.27 1.27)
				)
				(justify mirror)
			)
		)
		(property "Value" ""
			(at 0 0 0)
			(layer "B.Fab")
			(effects
				(font
					(size 1.27 1.27)
				)
				(justify mirror)
			)
		)
		(duplicate_pad_numbers_are_jumpers no)
		(fp_line
			(start -1.524 -0.762)
			(end -1.524 0.762)
			(stroke
				(width 0.1524)
				(type default)
			)
			(layer "B.SilkS")
		)
		(fp_line
			(start -1.524 0.762)
			(end 1.524 0.762)
			(stroke
				(width 0.1524)
				(type default)
			)
			(layer "B.SilkS")
		)
		(fp_line
			(start 1.524 -0.762)
			(end -1.524 -0.762)
			(stroke
				(width 0.1524)
				(type default)
			)
			(layer "B.SilkS")
		)
		(fp_line
			(start 1.524 0.762)
			(end 1.524 -0.762)
			(stroke
				(width 0.1524)
				(type default)
			)
			(layer "B.SilkS")
		)
		(fp_line
			(start -1.1049 -0.724916)
			(end 1.1049 -0.724916)
			(stroke
				(width 0.1)
				(type default)
			)
			(layer "B.Fab")
		)
		(fp_line
			(start -1.1049 0.724916)
			(end -1.1049 -0.724916)
			(stroke
				(width 0.1)
				(type default)
			)
			(layer "B.Fab")
		)
		(fp_line
			(start 1.1049 -0.724916)
			(end 1.1049 0.724916)
			(stroke
				(width 0.1)
				(type default)
			)
			(layer "B.Fab")
		)
		(fp_line
			(start 1.1049 0.724916)
			(end -1.1049 0.724916)
			(stroke
				(width 0.1)
				(type default)
			)
			(layer "B.Fab")
		)
		(pad "1" smd rect
			(at 0.889 0)
			(size 1.016 1.27)
			(layers "B.Cu" "B.Mask" "B.Paste")
			(net "PVCCIN_CPU0")
		)
		(pad "2" smd rect
			(at -0.889 0)
			(size 1.016 1.27)
			(layers "B.Cu" "B.Mask" "B.Paste")
			(net "GND")
		)
	)
	(footprint ""
		(layer "B.Cu")
		(at 356.354888 -333.639922 90)
		(property "Reference" "PC304_P0_2"
			(at 0 0 90)
			(layer "B.SilkS")
			(hide yes)
			(effects
				(font
					(size 1.27 1.27)
				)
				(justify mirror)
			)
		)
		(property "Value" ""
			(at 0 0 90)
			(layer "B.Fab")
			(effects
				(font
					(size 1.27 1.27)
				)
				(justify mirror)
			)
		)
		(duplicate_pad_numbers_are_jumpers no)
		(fp_line
			(start 1.524 -0.762)
			(end -1.524 -0.762)
			(stroke
				(width 0.1524)
				(type default)
			)
			(layer "B.SilkS")
		)
		(fp_line
			(start -1.524 -0.762)
			(end -1.524 0.762)
			(stroke
				(width 0.1524)
				(type default)
			)
			(layer "B.SilkS")
		)
		(fp_line
			(start 1.524 0.762)
			(end 1.524 -0.762)
			(stroke
				(width 0.1524)
				(type default)
			)
			(layer "B.SilkS")
		)
		(fp_line
			(start -1.524 0.762)
			(end 1.524 0.762)
			(stroke
				(width 0.1524)
				(type default)
			)
			(layer "B.SilkS")
		)
		(fp_line
			(start 1.1049 -0.724916)
			(end 1.1049 0.724916)
			(stroke
				(width 0.1)
				(type default)
			)
			(layer "B.Fab")
		)
		(fp_line
			(start -1.1049 -0.724916)
			(end 1.1049 -0.724916)
			(stroke
				(width 0.1)
				(type default)
			)
			(layer "B.Fab")
		)
		(fp_line
			(start 1.1049 0.724916)
			(end -1.1049 0.724916)
			(stroke
				(width 0.1)
				(type default)
			)
			(layer "B.Fab")
		)
		(fp_line
			(start -1.1049 0.724916)
			(end -1.1049 -0.724916)
			(stroke
				(width 0.1)
				(type default)
			)
			(layer "B.Fab")
		)
		(pad "1" smd rect
			(at 0.889 0 90)
			(size 1.016 1.27)
			(layers "B.Cu" "B.Mask" "B.Paste")
			(net "SW_P12V_PVCCIN_CPU0_FLT")
		)
		(pad "2" smd rect
			(at -0.889 0 90)
			(size 1.016 1.27)
			(layers "B.Cu" "B.Mask" "B.Paste")
			(net "GND")
		)
	)
	(footprint ""
		(layer "B.Cu")
		(at 292.231572 -354.163376 -90)
		(property "Reference" "PC1186_P0_4"
			(at 0 0 90)
			(layer "B.SilkS")
			(hide yes)
			(effects
				(font
					(size 1.27 1.27)
				)
				(justify mirror)
			)
		)
		(property "Value" ""
			(at 0 0 90)
			(layer "B.Fab")
			(effects
				(font
					(size 1.27 1.27)
				)
				(justify mirror)
			)
		)
		(duplicate_pad_numbers_are_jumpers no)
		(fp_line
			(start -1.524 0.762)
			(end 1.524 0.762)
			(stroke
				(width 0.1524)
				(type default)
			)
			(layer "B.SilkS")
		)
		(fp_line
			(start 1.524 0.762)
			(end 1.524 -0.762)
			(stroke
				(width 0.1524)
				(type default)
			)
			(layer "B.SilkS")
		)
		(fp_line
			(start -1.524 -0.762)
			(end -1.524 0.762)
			(stroke
				(width 0.1524)
				(type default)
			)
			(layer "B.SilkS")
		)
		(fp_line
			(start 1.524 -0.762)
			(end -1.524 -0.762)
			(stroke
				(width 0.1524)
				(type default)
			)
			(layer "B.SilkS")
		)
		(fp_line
			(start -1.1049 0.724916)
			(end -1.1049 -0.724916)
			(stroke
				(width 0.1)
				(type default)
			)
			(layer "B.Fab")
		)
		(fp_line
			(start 1.1049 0.724916)
			(end -1.1049 0.724916)
			(stroke
				(width 0.1)
				(type default)
			)
			(layer "B.Fab")
		)
		(fp_line
			(start -1.1049 -0.724916)
			(end 1.1049 -0.724916)
			(stroke
				(width 0.1)
				(type default)
			)
			(layer "B.Fab")
		)
		(fp_line
			(start 1.1049 -0.724916)
			(end 1.1049 0.724916)
			(stroke
				(width 0.1)
				(type default)
			)
			(layer "B.Fab")
		)
		(pad "1" smd rect
			(at 0.889 0 270)
			(size 1.016 1.27)
			(layers "B.Cu" "B.Mask" "B.Paste")
			(net "PVCCFA_EHV_FIVRA_CPU0")
		)
		(pad "2" smd rect
			(at -0.889 0 270)
			(size 1.016 1.27)
			(layers "B.Cu" "B.Mask" "B.Paste")
			(net "GND")
		)
	)
)
